FILE_TYPE = MACRO_DRAWING;
SET COLOR_WIRE YELLOW;
SET COLOR_PROP ORANGE;
SET COLOR_DOT WHITE;
SET COLOR_ARC YELLOW;
SET COLOR_BODY GREEN;
SET COLOR_NOTE PURPLE;
SET PROP_DISPLAY VALUE;
SET PAGE_NUMBER P347;
FORCEADD QUANTA_TITLE_BLOCK_C..1
(-6500 -2200);
FORCEPROP 1 LAST Q_TITLE Blank
J 0
(-15791 -2174);
DISPLAY 2.446809 (-15791 -2174);
PAINT GREEN (-15791 -2174);
FORCEPROP 2 LAST CUSTOM_TXT_CDS <NAME_2>
J 0
(-9675 -2150);
FORCEPROP 2 LAST CUSTOM_TXT_CDS <NAME_1>
J 0
(-9675 -2025);
FORCEPROP 2 LAST CUSTOM_TXT_CDS <Q_NUMBER>
J 0
(-7903 -2097);
DISPLAY 1.212766 (-7903 -2097);
FORCEPROP 2 LAST CUSTOM_TXT_CDS <Q_PROJ>
J 0
(-8882 -2098);
DISPLAY 1.212766 (-8882 -2098);
FORCEPROP 2 LAST CUSTOM_TXT_CDS <Q_REV>
J 0
(-6684 -2097);
DISPLAY 1.212766 (-6684 -2097);
FORCEPROP 2 LAST CUSTOM_TXT_CDS <CON_PAGE_NUM> OF <CON_TOTAL_PAGES>
J 0
(-6946 -2182);
DISPLAY 0.978723 (-6946 -2182);
FORCEPROP 2 LAST CUSTOM_TXT_CDS <CON_LAST_MODIFIED>
J 0
(-8385 -2185);
DISPLAY 0.978723 (-8385 -2185);
FORCEPROP 2 LAST PAGE_BORDER TRUE
J 0
(-14390 3050);
DISPLAY 0.638298 (-14390 3050);
PAINT PINK (-14390 3050);
DISPLAY INVISIBLE (-14390 3050);
FORCEPROP 1 LAST CDS_LMAN_SYM_OUTLINE -9475,6775,100,-125
J 0
(-6500 -2200);
DISPLAY 0.468085 (-6500 -2200);
PAINT GREEN (-6500 -2200);
DISPLAY INVISIBLE (-6500 -2200);
FORCEPROP 2 LAST CDS_LIB pure_quanta
J 0
(-6500 -2200);
PAINT MONO (-6500 -2200);
DISPLAY INVISIBLE (-6500 -2200);
FORCEPROP 2 LAST CDS_XR_PAGE_TITLE CR-149 : @T6G_MB_LIB.T6G(SCH_1):PAGE149
J 0
(-14390 3050);
DISPLAY 0.638298 (-14390 3050);
PAINT PINK (-14390 3050);
DISPLAY INVISIBLE (-14390 3050);
FORCEPROP 2 LAST CUSTOM_TXT_CDS <XR_PAGE_TITLE>
J 0
(-14390 3050);
DISPLAY 0.638298 (-14390 3050);
PAINT PINK (-14390 3050);
DISPLAY INVISIBLE (-14390 3050);
FORCEPROP 1 LAST COMMENT_BODY TRUE
J 0
(-6488 -2213);
DISPLAY 0.978723 (-6488 -2213);
PAINT GREEN (-6488 -2213);
DISPLAY INVISIBLE (-6488 -2213);
FORCEPROP 1 LAST Q_DEPT BU9
J 1
(-10263 -2151);
DISPLAY 1.957447 (-10263 -2151);
PAINT GREEN (-10263 -2151);
DISPLAY INVISIBLE (-10263 -2151);
FORCEPROP 0 LAST CDS_CON_LAST_MODIFIED Thu Aug 24 10:14:39 2023
J 0
(-8385 -2185);
PAINT MONO (-8385 -2185);
DISPLAY INVISIBLE (-8385 -2185);
QUIT
